(kicad_pcb
	(version 20260206)
	(generator "pcbnew")
	(generator_version "10.0")
	(general
		(thickness 1.6)
		(legacy_teardrops no)
	)
	(paper "A4")
	(title_block
		(title "04192023_DAF0TMB3IC0_F0TG_MB_C_brd_V02_OCP.brd")
		(comment 1 "Grand Teton / footprint 3955 of 8354 (U25), pads 3225-3333 of 6102")
	)
	(layers
		(0 "F.Cu" signal "TOP")
		(4 "In1.Cu" signal "GND")
		(6 "In2.Cu" signal "IN1")
		(8 "In3.Cu" signal "GND1")
		(10 "In4.Cu" signal "IN2")
		(12 "In5.Cu" signal "GND2")
		(14 "In6.Cu" signal "IN3")
		(16 "In7.Cu" signal "GND3")
		(18 "In8.Cu" signal "VCC")
		(20 "In9.Cu" signal "VCC1")
		(22 "In10.Cu" signal "GND4")
		(24 "In11.Cu" signal "IN4")
		(26 "In12.Cu" signal "GND5")
		(28 "In13.Cu" signal "IN5")
		(30 "In14.Cu" signal "GND6")
		(32 "In15.Cu" signal "IN6")
		(34 "In16.Cu" signal "GND7")
		(2 "B.Cu" signal "BOTTOM")
		(9 "F.Adhes" user "F.Adhesive")
		(11 "B.Adhes" user "B.Adhesive")
		(13 "F.Paste" user "Package Geometry/Pastemask Top")
		(15 "B.Paste" user "Package Geometry/Pastemask Bottom")
		(5 "F.SilkS" user "Ref Des/Silkscreen Top")
		(7 "B.SilkS" user "Ref Des/Silkscreen Bottom")
		(1 "F.Mask" user "Board Geometry/Soldermask Top")
		(3 "B.Mask" user "Board Geometry/Soldermask Bottom")
		(17 "Dwgs.User" user "User.Drawings")
		(19 "Cmts.User" user "User.Comments")
		(21 "Eco1.User" user "User.Eco1")
		(23 "Eco2.User" user "User.Eco2")
		(25 "Edge.Cuts" user "Board Geometry/Outline")
		(27 "Margin" user)
		(31 "F.CrtYd" user "Package Geometry/Place Bound Top")
		(29 "B.CrtYd" user "Package Geometry/Place Bound Bottom")
		(35 "F.Fab" user "Ref Des/Assembly Top")
		(33 "B.Fab" user "Ref Des/Assembly Bottom")
	)
	(footprint ""
		(layer "F.Cu")
		(at 359.867962 -258.880102 180)
		(property "Reference" "U25"
			(at -45.78477 -62.086744 0)
			(unlocked yes)
			(layer "F.SilkS")
			(effects
				(font
					(size 0.7874 0.5842)
					(thickness 0.1524)
				)
			)
		)
		(property "Value" ""
			(at 0 0 180)
			(layer "F.Fab")
			(effects
				(font
					(size 1.27 1.27)
				)
			)
		)
		(duplicate_pad_numbers_are_jumpers no)
		(pad "CF59" smd circle
			(at 19.590004 18.18005 180)
			(size 0.450088 0.450088)
			(layers "F.Cu" "F.Mask" "F.Paste")
			(net "GND")
		)
		(pad "CF60" smd circle
			(at 20.530058 18.18005 180)
			(size 0.450088 0.450088)
			(layers "F.Cu" "F.Mask" "F.Paste")
			(net "M_D_CPU0_SB_DQ<4>")
		)
		(pad "CF61" smd circle
			(at 21.470112 18.18005 180)
			(size 0.450088 0.450088)
			(layers "F.Cu" "F.Mask" "F.Paste")
			(net "GND")
		)
		(pad "CF62" smd circle
			(at 22.409912 18.18005 180)
			(size 0.450088 0.450088)
			(layers "F.Cu" "F.Mask" "F.Paste")
			(net "M_B_CPU0_SB_DQS_DP<5>")
		)
		(pad "CF63" smd circle
			(at 23.349966 18.18005 180)
			(size 0.450088 0.450088)
			(layers "F.Cu" "F.Mask" "F.Paste")
			(net "M_B_CPU0_SB_DQ<4>")
		)
		(pad "CF64" smd circle
			(at 24.29002 18.18005 180)
			(size 0.450088 0.450088)
			(layers "F.Cu" "F.Mask" "F.Paste")
			(net "GND")
		)
		(pad "CF65" smd circle
			(at 25.230074 18.18005 180)
			(size 0.450088 0.450088)
			(layers "F.Cu" "F.Mask" "F.Paste")
			(net "M_F_CPU0_SB_DQS_DP<5>")
		)
		(pad "CF66" smd circle
			(at 26.170128 18.18005 180)
			(size 0.450088 0.450088)
			(layers "F.Cu" "F.Mask" "F.Paste")
			(net "GND")
		)
		(pad "CF67" smd circle
			(at 27.109928 18.18005 180)
			(size 0.450088 0.450088)
			(layers "F.Cu" "F.Mask" "F.Paste")
			(net "M_F_CPU0_SB_DQ<4>")
		)
		(pad "CF68" smd circle
			(at 28.049982 18.18005 180)
			(size 0.450088 0.450088)
			(layers "F.Cu" "F.Mask" "F.Paste")
			(net "GND")
		)
		(pad "CF69" smd circle
			(at 28.990036 18.18005 180)
			(size 0.450088 0.450088)
			(layers "F.Cu" "F.Mask" "F.Paste")
			(net "M_E_CPU0_SB_DQS_DP<5>")
		)
		(pad "CF70" smd circle
			(at 29.93009 18.18005 180)
			(size 0.450088 0.450088)
			(layers "F.Cu" "F.Mask" "F.Paste")
			(net "M_E_CPU0_SB_DQ<4>")
		)
		(pad "CF71" smd circle
			(at 30.86989 18.18005 180)
			(size 0.450088 0.450088)
			(layers "F.Cu" "F.Mask" "F.Paste")
			(net "GND")
		)
		(pad "CF72" smd circle
			(at 31.809944 18.18005 180)
			(size 0.450088 0.450088)
			(layers "F.Cu" "F.Mask" "F.Paste")
			(net "M_A_CPU0_SB_DQS_DP<5>")
		)
		(pad "CF73" smd circle
			(at 32.749998 18.18005 180)
			(size 0.450088 0.450088)
			(layers "F.Cu" "F.Mask" "F.Paste")
			(net "GND")
		)
		(pad "CF74" smd circle
			(at 33.690052 18.18005 180)
			(size 0.450088 0.450088)
			(layers "F.Cu" "F.Mask" "F.Paste")
			(net "M_A_CPU0_SB_DQ<4>")
		)
		(pad "CG1" smd circle
			(at -34.459926 18.990056 180)
			(size 0.450088 0.450088)
			(layers "F.Cu" "F.Mask" "F.Paste")
			(net "GND")
		)
		(pad "CG2" smd circle
			(at -33.519872 18.990056 180)
			(size 0.450088 0.450088)
			(layers "F.Cu" "F.Mask" "F.Paste")
			(net "M_G_CPU0_SB_DQ<6>")
		)
		(pad "CG3" smd circle
			(at -32.580072 18.990056 180)
			(size 0.450088 0.450088)
			(layers "F.Cu" "F.Mask" "F.Paste")
			(net "M_G_CPU0_SB_DQ<5>")
		)
		(pad "CG4" smd circle
			(at -31.640018 18.990056 180)
			(size 0.450088 0.450088)
			(layers "F.Cu" "F.Mask" "F.Paste")
			(net "PVDD11_S3_P0")
		)
		(pad "CG5" smd circle
			(at -30.699964 18.990056 180)
			(size 0.450088 0.450088)
			(layers "F.Cu" "F.Mask" "F.Paste")
			(net "M_K_CPU0_SB_DQ<6>")
		)
		(pad "CG6" smd circle
			(at -29.75991 18.990056 180)
			(size 0.450088 0.450088)
			(layers "F.Cu" "F.Mask" "F.Paste")
			(net "GND")
		)
		(pad "CG7" smd circle
			(at -28.82011 18.990056 180)
			(size 0.450088 0.450088)
			(layers "F.Cu" "F.Mask" "F.Paste")
			(net "M_K_CPU0_SB_DQ<5>")
		)
		(pad "CG8" smd circle
			(at -27.880056 18.990056 180)
			(size 0.450088 0.450088)
			(layers "F.Cu" "F.Mask" "F.Paste")
			(net "GND")
		)
		(pad "CG9" smd circle
			(at -26.940002 18.990056 180)
			(size 0.450088 0.450088)
			(layers "F.Cu" "F.Mask" "F.Paste")
			(net "M_L_CPU0_SB_DQ<6>")
		)
		(pad "CG10" smd circle
			(at -25.999948 18.990056 180)
			(size 0.450088 0.450088)
			(layers "F.Cu" "F.Mask" "F.Paste")
			(net "M_L_CPU0_SB_DQ<5>")
		)
		(pad "CG11" smd circle
			(at -25.059894 18.990056 180)
			(size 0.450088 0.450088)
			(layers "F.Cu" "F.Mask" "F.Paste")
			(net "PVDD11_S3_P0")
		)
		(pad "CG12" smd circle
			(at -24.120094 18.990056 180)
			(size 0.450088 0.450088)
			(layers "F.Cu" "F.Mask" "F.Paste")
			(net "M_H_CPU0_SB_DQ<6>")
		)
		(pad "CG13" smd circle
			(at -23.18004 18.990056 180)
			(size 0.450088 0.450088)
			(layers "F.Cu" "F.Mask" "F.Paste")
			(net "GND")
		)
		(pad "CG14" smd circle
			(at -22.239986 18.990056 180)
			(size 0.450088 0.450088)
			(layers "F.Cu" "F.Mask" "F.Paste")
			(net "M_H_CPU0_SB_DQ<5>")
		)
		(pad "CG15" smd circle
			(at -21.299932 18.990056 180)
			(size 0.450088 0.450088)
			(layers "F.Cu" "F.Mask" "F.Paste")
			(net "GND")
		)
		(pad "CG16" smd circle
			(at -20.359878 18.990056 180)
			(size 0.450088 0.450088)
			(layers "F.Cu" "F.Mask" "F.Paste")
			(net "M_J_CPU0_SB_DQ<6>")
		)
		(pad "CG17" smd circle
			(at -19.420078 18.990056 180)
			(size 0.450088 0.450088)
			(layers "F.Cu" "F.Mask" "F.Paste")
			(net "M_J_CPU0_SB_DQ<5>")
		)
		(pad "CG18" smd circle
			(at -18.480024 18.990056 180)
			(size 0.450088 0.450088)
			(layers "F.Cu" "F.Mask" "F.Paste")
			(net "PVDD11_S3_P0")
		)
		(pad "CG19" smd circle
			(at -17.53997 18.990056 180)
			(size 0.450088 0.450088)
			(layers "F.Cu" "F.Mask" "F.Paste")
			(net "M_I_CPU0_SB_DQ<6>")
		)
		(pad "CG20" smd circle
			(at -16.599916 18.990056 180)
			(size 0.450088 0.450088)
			(layers "F.Cu" "F.Mask" "F.Paste")
			(net "GND")
		)
		(pad "CG21" smd circle
			(at -15.660116 18.990056 180)
			(size 0.450088 0.450088)
			(layers "F.Cu" "F.Mask" "F.Paste")
			(net "M_I_CPU0_SB_DQ<5>")
		)
		(pad "CG22" smd circle
			(at -14.720062 18.990056 180)
			(size 0.450088 0.450088)
			(layers "F.Cu" "F.Mask" "F.Paste")
			(net "GND")
		)
		(pad "CG23" smd circle
			(at -13.780008 18.990056 180)
			(size 0.450088 0.450088)
			(layers "F.Cu" "F.Mask" "F.Paste")
			(net "P5E_CPU0_P3_TX_DN<14>")
		)
		(pad "CG24" smd circle
			(at -12.839954 18.990056 180)
			(size 0.450088 0.450088)
			(layers "F.Cu" "F.Mask" "F.Paste")
			(net "P5E_CPU0_P3_TX_DP<14>")
		)
		(pad "CG25" smd circle
			(at -11.8999 18.990056 180)
			(size 0.450088 0.450088)
			(layers "F.Cu" "F.Mask" "F.Paste")
			(net "GND")
		)
		(pad "CG26" smd circle
			(at -10.9601 18.990056 180)
			(size 0.450088 0.450088)
			(layers "F.Cu" "F.Mask" "F.Paste")
			(net "P5E_CPU0_P3_TX_DN<11>")
		)
		(pad "CG27" smd circle
			(at -10.020046 18.990056 180)
			(size 0.450088 0.450088)
			(layers "F.Cu" "F.Mask" "F.Paste")
			(net "P5E_CPU0_P3_TX_DP<11>")
		)
		(pad "CG28" smd circle
			(at -9.079992 18.990056 180)
			(size 0.450088 0.450088)
			(layers "F.Cu" "F.Mask" "F.Paste")
			(net "GND")
		)
		(pad "CG29" smd circle
			(at -8.139938 18.990056 180)
			(size 0.450088 0.450088)
			(layers "F.Cu" "F.Mask" "F.Paste")
			(net "P5E_CPU0_P3_TX_DN<8>")
		)
		(pad "CG30" smd circle
			(at -7.199884 18.990056 180)
			(size 0.450088 0.450088)
			(layers "F.Cu" "F.Mask" "F.Paste")
			(net "P5E_CPU0_P3_TX_DP<8>")
		)
		(pad "CG31" smd circle
			(at -6.260084 18.990056 180)
			(size 0.450088 0.450088)
			(layers "F.Cu" "F.Mask" "F.Paste")
			(net "GND")
		)
		(pad "CG32" smd circle
			(at -5.32003 18.990056 180)
			(size 0.450088 0.450088)
			(layers "F.Cu" "F.Mask" "F.Paste")
			(net "P5E_CPU0_P3_TX_DN<5>")
		)
		(pad "CG33" smd circle
			(at -4.379976 18.990056 180)
			(size 0.450088 0.450088)
			(layers "F.Cu" "F.Mask" "F.Paste")
			(net "P5E_CPU0_P3_TX_DP<5>")
		)
		(pad "CG34" smd circle
			(at -3.439922 18.990056 180)
			(size 0.450088 0.450088)
			(layers "F.Cu" "F.Mask" "F.Paste")
			(net "GND")
		)
		(pad "CG35" smd circle
			(at -2.500122 18.990056 180)
			(size 0.450088 0.450088)
			(layers "F.Cu" "F.Mask" "F.Paste")
			(net "PVDDCR_CPU1_P0")
		)
		(pad "CG36" smd circle
			(at -1.560068 18.990056 180)
			(size 0.450088 0.450088)
			(layers "F.Cu" "F.Mask" "F.Paste")
			(net "PVDDCR_CPU1_P0")
		)
		(pad "CG40" smd circle
			(at 1.260094 18.990056 180)
			(size 0.450088 0.450088)
			(layers "F.Cu" "F.Mask" "F.Paste")
			(net "PVDDCR_CPU1_P0")
		)
		(pad "CG41" smd circle
			(at 2.199894 18.990056 180)
			(size 0.450088 0.450088)
			(layers "F.Cu" "F.Mask" "F.Paste")
			(net "PVDDCR_CPU1_P0")
		)
		(pad "CG42" smd circle
			(at 3.139948 18.990056 180)
			(size 0.450088 0.450088)
			(layers "F.Cu" "F.Mask" "F.Paste")
			(net "GND")
		)
		(pad "CG43" smd circle
			(at 4.080002 18.990056 180)
			(size 0.450088 0.450088)
			(layers "F.Cu" "F.Mask" "F.Paste")
			(net "P5E_CPU0_P1_RX_DP<10>")
		)
		(pad "CG44" smd circle
			(at 5.020056 18.990056 180)
			(size 0.450088 0.450088)
			(layers "F.Cu" "F.Mask" "F.Paste")
			(net "P5E_CPU0_P1_RX_DN<10>")
		)
		(pad "CG45" smd circle
			(at 5.96011 18.990056 180)
			(size 0.450088 0.450088)
			(layers "F.Cu" "F.Mask" "F.Paste")
			(net "GND")
		)
		(pad "CG46" smd circle
			(at 6.89991 18.990056 180)
			(size 0.450088 0.450088)
			(layers "F.Cu" "F.Mask" "F.Paste")
			(net "P5E_CPU0_P1_RX_DP<7>")
		)
		(pad "CG47" smd circle
			(at 7.839964 18.990056 180)
			(size 0.450088 0.450088)
			(layers "F.Cu" "F.Mask" "F.Paste")
			(net "P5E_CPU0_P1_RX_DN<7>")
		)
		(pad "CG48" smd circle
			(at 8.780018 18.990056 180)
			(size 0.450088 0.450088)
			(layers "F.Cu" "F.Mask" "F.Paste")
			(net "GND")
		)
		(pad "CG49" smd circle
			(at 9.720072 18.990056 180)
			(size 0.450088 0.450088)
			(layers "F.Cu" "F.Mask" "F.Paste")
			(net "P5E_CPU0_P1_RX_DP<4>")
		)
		(pad "CG50" smd circle
			(at 10.659872 18.990056 180)
			(size 0.450088 0.450088)
			(layers "F.Cu" "F.Mask" "F.Paste")
			(net "P5E_CPU0_P1_RX_DN<4>")
		)
		(pad "CG51" smd circle
			(at 11.599926 18.990056 180)
			(size 0.450088 0.450088)
			(layers "F.Cu" "F.Mask" "F.Paste")
			(net "GND")
		)
		(pad "CG52" smd circle
			(at 12.53998 18.990056 180)
			(size 0.450088 0.450088)
			(layers "F.Cu" "F.Mask" "F.Paste")
			(net "P5E_CPU0_P1_RX_DP<1>")
		)
		(pad "CG53" smd circle
			(at 13.480034 18.990056 180)
			(size 0.450088 0.450088)
			(layers "F.Cu" "F.Mask" "F.Paste")
			(net "P5E_CPU0_P1_RX_DN<1>")
		)
		(pad "CG54" smd circle
			(at 14.420088 18.990056 180)
			(size 0.450088 0.450088)
			(layers "F.Cu" "F.Mask" "F.Paste")
			(net "GND")
		)
		(pad "CG55" smd circle
			(at 15.359888 18.990056 180)
			(size 0.450088 0.450088)
			(layers "F.Cu" "F.Mask" "F.Paste")
			(net "M_C_CPU0_SB_DQ<5>")
		)
		(pad "CG56" smd circle
			(at 16.299942 18.990056 180)
			(size 0.450088 0.450088)
			(layers "F.Cu" "F.Mask" "F.Paste")
			(net "GND")
		)
		(pad "CG57" smd circle
			(at 17.239996 18.990056 180)
			(size 0.450088 0.450088)
			(layers "F.Cu" "F.Mask" "F.Paste")
			(net "M_C_CPU0_SB_DQ<6>")
		)
		(pad "CG58" smd circle
			(at 18.18005 18.990056 180)
			(size 0.450088 0.450088)
			(layers "F.Cu" "F.Mask" "F.Paste")
			(net "PVDDIO_P0")
		)
		(pad "CG59" smd circle
			(at 19.120104 18.990056 180)
			(size 0.450088 0.450088)
			(layers "F.Cu" "F.Mask" "F.Paste")
			(net "M_D_CPU0_SB_DQ<5>")
		)
		(pad "CG60" smd circle
			(at 20.059904 18.990056 180)
			(size 0.450088 0.450088)
			(layers "F.Cu" "F.Mask" "F.Paste")
			(net "M_D_CPU0_SB_DQ<6>")
		)
		(pad "CG61" smd circle
			(at 20.999958 18.990056 180)
			(size 0.450088 0.450088)
			(layers "F.Cu" "F.Mask" "F.Paste")
			(net "GND")
		)
		(pad "CG62" smd circle
			(at 21.940012 18.990056 180)
			(size 0.450088 0.450088)
			(layers "F.Cu" "F.Mask" "F.Paste")
			(net "M_B_CPU0_SB_DQ<5>")
		)
		(pad "CG63" smd circle
			(at 22.880066 18.990056 180)
			(size 0.450088 0.450088)
			(layers "F.Cu" "F.Mask" "F.Paste")
			(net "GND")
		)
		(pad "CG64" smd circle
			(at 23.82012 18.990056 180)
			(size 0.450088 0.450088)
			(layers "F.Cu" "F.Mask" "F.Paste")
			(net "M_B_CPU0_SB_DQ<6>")
		)
		(pad "CG65" smd circle
			(at 24.75992 18.990056 180)
			(size 0.450088 0.450088)
			(layers "F.Cu" "F.Mask" "F.Paste")
			(net "PVDDIO_P0")
		)
		(pad "CG66" smd circle
			(at 25.699974 18.990056 180)
			(size 0.450088 0.450088)
			(layers "F.Cu" "F.Mask" "F.Paste")
			(net "M_F_CPU0_SB_DQ<5>")
		)
		(pad "CG67" smd circle
			(at 26.640028 18.990056 180)
			(size 0.450088 0.450088)
			(layers "F.Cu" "F.Mask" "F.Paste")
			(net "M_F_CPU0_SB_DQ<6>")
		)
		(pad "CG68" smd circle
			(at 27.580082 18.990056 180)
			(size 0.450088 0.450088)
			(layers "F.Cu" "F.Mask" "F.Paste")
			(net "GND")
		)
		(pad "CG69" smd circle
			(at 28.519882 18.990056 180)
			(size 0.450088 0.450088)
			(layers "F.Cu" "F.Mask" "F.Paste")
			(net "M_E_CPU0_SB_DQ<5>")
		)
		(pad "CG70" smd circle
			(at 29.459936 18.990056 180)
			(size 0.450088 0.450088)
			(layers "F.Cu" "F.Mask" "F.Paste")
			(net "GND")
		)
		(pad "CG71" smd circle
			(at 30.39999 18.990056 180)
			(size 0.450088 0.450088)
			(layers "F.Cu" "F.Mask" "F.Paste")
			(net "M_E_CPU0_SB_DQ<6>")
		)
		(pad "CG72" smd circle
			(at 31.340044 18.990056 180)
			(size 0.450088 0.450088)
			(layers "F.Cu" "F.Mask" "F.Paste")
			(net "PVDDIO_P0")
		)
		(pad "CG73" smd circle
			(at 32.280098 18.990056 180)
			(size 0.450088 0.450088)
			(layers "F.Cu" "F.Mask" "F.Paste")
			(net "M_A_CPU0_SB_DQ<5>")
		)
		(pad "CG74" smd circle
			(at 33.219898 18.990056 180)
			(size 0.450088 0.450088)
			(layers "F.Cu" "F.Mask" "F.Paste")
			(net "M_A_CPU0_SB_DQ<6>")
		)
		(pad "CG75" smd circle
			(at 34.159952 18.990056 180)
			(size 0.450088 0.450088)
			(layers "F.Cu" "F.Mask" "F.Paste")
			(net "GND")
		)
		(pad "CH2" smd circle
			(at -33.990026 19.800062 180)
			(size 0.450088 0.450088)
			(layers "F.Cu" "F.Mask" "F.Paste")
			(net "M_G_CPU0_SB_DQ<8>")
		)
		(pad "CH3" smd circle
			(at -33.049972 19.800062 180)
			(size 0.450088 0.450088)
			(layers "F.Cu" "F.Mask" "F.Paste")
			(net "GND")
		)
		(pad "CH4" smd circle
			(at -32.109918 19.800062 180)
			(size 0.450088 0.450088)
			(layers "F.Cu" "F.Mask" "F.Paste")
			(net "M_G_CPU0_SB_DQ<7>")
		)
		(pad "CH5" smd circle
			(at -31.170118 19.800062 180)
			(size 0.450088 0.450088)
			(layers "F.Cu" "F.Mask" "F.Paste")
			(net "GND")
		)
		(pad "CH6" smd circle
			(at -30.230064 19.800062 180)
			(size 0.450088 0.450088)
			(layers "F.Cu" "F.Mask" "F.Paste")
			(net "M_K_CPU0_SB_DQ<8>")
		)
		(pad "CH7" smd circle
			(at -29.29001 19.800062 180)
			(size 0.450088 0.450088)
			(layers "F.Cu" "F.Mask" "F.Paste")
			(net "M_K_CPU0_SB_DQ<7>")
		)
		(pad "CH8" smd circle
			(at -28.349956 19.800062 180)
			(size 0.450088 0.450088)
			(layers "F.Cu" "F.Mask" "F.Paste")
			(net "GND")
		)
		(pad "CH9" smd circle
			(at -27.409902 19.800062 180)
			(size 0.450088 0.450088)
			(layers "F.Cu" "F.Mask" "F.Paste")
			(net "M_L_CPU0_SB_DQ<8>")
		)
		(pad "CH10" smd circle
			(at -26.470102 19.800062 180)
			(size 0.450088 0.450088)
			(layers "F.Cu" "F.Mask" "F.Paste")
			(net "GND")
		)
		(pad "CH11" smd circle
			(at -25.530048 19.800062 180)
			(size 0.450088 0.450088)
			(layers "F.Cu" "F.Mask" "F.Paste")
			(net "M_L_CPU0_SB_DQ<7>")
		)
		(pad "CH12" smd circle
			(at -24.589994 19.800062 180)
			(size 0.450088 0.450088)
			(layers "F.Cu" "F.Mask" "F.Paste")
			(net "GND")
		)
		(pad "CH13" smd circle
			(at -23.64994 19.800062 180)
			(size 0.450088 0.450088)
			(layers "F.Cu" "F.Mask" "F.Paste")
			(net "M_H_CPU0_SB_DQ<8>")
		)
		(pad "CH14" smd circle
			(at -22.709886 19.800062 180)
			(size 0.450088 0.450088)
			(layers "F.Cu" "F.Mask" "F.Paste")
			(net "M_H_CPU0_SB_DQ<7>")
		)
		(pad "CH15" smd circle
			(at -21.770086 19.800062 180)
			(size 0.450088 0.450088)
			(layers "F.Cu" "F.Mask" "F.Paste")
			(net "GND")
		)
		(pad "CH16" smd circle
			(at -20.830032 19.800062 180)
			(size 0.450088 0.450088)
			(layers "F.Cu" "F.Mask" "F.Paste")
			(net "M_J_CPU0_SB_DQ<8>")
		)
		(pad "CH17" smd circle
			(at -19.889978 19.800062 180)
			(size 0.450088 0.450088)
			(layers "F.Cu" "F.Mask" "F.Paste")
			(net "GND")
		)
		(pad "CH18" smd circle
			(at -18.949924 19.800062 180)
			(size 0.450088 0.450088)
			(layers "F.Cu" "F.Mask" "F.Paste")
			(net "M_J_CPU0_SB_DQ<7>")
		)
		(pad "CH19" smd circle
			(at -18.010124 19.800062 180)
			(size 0.450088 0.450088)
			(layers "F.Cu" "F.Mask" "F.Paste")
			(net "GND")
		)
		(pad "CH20" smd circle
			(at -17.07007 19.800062 180)
			(size 0.450088 0.450088)
			(layers "F.Cu" "F.Mask" "F.Paste")
			(net "M_I_CPU0_SB_DQ<8>")
		)
		(pad "CH21" smd circle
			(at -16.130016 19.800062 180)
			(size 0.450088 0.450088)
			(layers "F.Cu" "F.Mask" "F.Paste")
			(net "M_I_CPU0_SB_DQ<7>")
		)
		(pad "CH22" smd circle
			(at -15.189962 19.800062 180)
			(size 0.450088 0.450088)
			(layers "F.Cu" "F.Mask" "F.Paste")
			(net "GND")
		)
	)
)
